# S9S_MB_2U (Grand Teton) — schematic netlist excerpt (pin names and nets, part order shuffled) for the footprints in the layout excerpt that follows; sources: Cadence DE-HDL packaged netlist, KiCad conversion of 03242023_DA0F0TMBIJ0_F0T_Motherboard_J_brd_V01_OCP.brd

C153  Q_CAP_DIFFBUS  DIFF BUS_0.22UF 6.3V 20% X6S  pkg C0201  page 178 : \1\ = DMI_CPU0_PCH_TX_C_DN<0> ; \2\ = DMI_CPU0_PCH_TX_DN<0>
R4100  Q_RES  10K 1% CHIP  pkg 0402LF  page 183 : A = PD_PCH_GPPC_C10 ; B = GND
PR3857  Q_RES  49.9 1% CHIP  pkg 0603LF  page 163 : A = P12V_AUX ; B = P12V_OCP_AVIN_PD_2

(kicad_pcb
	(version 20260206)
	(generator "pcbnew")
	(generator_version "10.0")
	(general
		(thickness 1.6)
		(legacy_teardrops no)
	)
	(paper "A4")
	(title_block
		(title "03242023_DA0F0TMBIJ0_F0T_Motherboard_J_brd_V01_OCP.brd")
		(comment 1 "Grand Teton / footprints 967-969 of 6105")
	)
	(layers
		(0 "F.Cu" signal "TOP")
		(4 "In1.Cu" signal "GND")
		(6 "In2.Cu" signal "IN1")
		(8 "In3.Cu" signal "GND1")
		(10 "In4.Cu" signal "IN2")
		(12 "In5.Cu" signal "GND2")
		(14 "In6.Cu" signal "IN3")
		(16 "In7.Cu" signal "GND3")
		(18 "In8.Cu" signal "VCC")
		(20 "In9.Cu" signal "VCC1")
		(22 "In10.Cu" signal "GND4")
		(24 "In11.Cu" signal "IN4")
		(26 "In12.Cu" signal "GND5")
		(28 "In13.Cu" signal "IN5")
		(30 "In14.Cu" signal "GND6")
		(32 "In15.Cu" signal "IN6")
		(34 "In16.Cu" signal "GND7")
		(2 "B.Cu" signal "BOTTOM")
		(9 "F.Adhes" user "F.Adhesive")
		(11 "B.Adhes" user "B.Adhesive")
		(13 "F.Paste" user "Package Geometry/Pastemask Top")
		(15 "B.Paste" user "Package Geometry/Pastemask Bottom")
		(5 "F.SilkS" user "Ref Des/Silkscreen Top")
		(7 "B.SilkS" user "Ref Des/Silkscreen Bottom")
		(1 "F.Mask" user "Board Geometry/Soldermask Top")
		(3 "B.Mask" user "Board Geometry/Soldermask Bottom")
		(17 "Dwgs.User" user "User.Drawings")
		(19 "Cmts.User" user "User.Comments")
		(21 "Eco1.User" user "User.Eco1")
		(23 "Eco2.User" user "User.Eco2")
		(25 "Edge.Cuts" user "Board Geometry/Outline")
		(27 "Margin" user)
		(31 "F.CrtYd" user "Package Geometry/Place Bound Top")
		(29 "B.CrtYd" user "Package Geometry/Place Bound Bottom")
		(35 "F.Fab" user "Ref Des/Assembly Top")
		(33 "B.Fab" user "Ref Des/Assembly Bottom")
	)
	(footprint ""
		(layer "F.Cu")
		(at 312.443622 -38.89121 180)
		(property "Reference" "R4100"
			(at 0 0 180)
			(layer "F.SilkS")
			(hide yes)
			(effects
				(font
					(size 1.27 1.27)
				)
			)
		)
		(property "Value" ""
			(at 0 0 180)
			(layer "F.Fab")
			(effects
				(font
					(size 1.27 1.27)
				)
			)
		)
		(duplicate_pad_numbers_are_jumpers no)
		(fp_line
			(start 0.7874 0.4064)
			(end -0.7874 0.4064)
			(stroke
				(width 0.1524)
				(type default)
			)
			(layer "F.SilkS")
		)
		(fp_line
			(start 0.7874 -0.4064)
			(end 0.7874 0.4064)
			(stroke
				(width 0.1524)
				(type default)
			)
			(layer "F.SilkS")
		)
		(fp_line
			(start -0.7874 0.4064)
			(end -0.7874 -0.4064)
			(stroke
				(width 0.1524)
				(type default)
			)
			(layer "F.SilkS")
		)
		(fp_line
			(start -0.7874 -0.4064)
			(end 0.7874 -0.4064)
			(stroke
				(width 0.1524)
				(type default)
			)
			(layer "F.SilkS")
		)
		(fp_line
			(start 0.67945 0.3048)
			(end 0.120396 0.3048)
			(stroke
				(width 0.1)
				(type default)
			)
			(layer "F.Fab")
		)
		(fp_line
			(start 0.67945 -0.3048)
			(end 0.67945 0.3048)
			(stroke
				(width 0.1)
				(type default)
			)
			(layer "F.Fab")
		)
		(fp_line
			(start 0.12065 -0.2794)
			(end 0.12065 -0.3048)
			(stroke
				(width 0.1)
				(type default)
			)
			(layer "F.Fab")
		)
		(fp_line
			(start 0.12065 -0.3048)
			(end 0.67945 -0.3048)
			(stroke
				(width 0.1)
				(type default)
			)
			(layer "F.Fab")
		)
		(fp_line
			(start 0.120396 0.3048)
			(end 0.120396 0.2794)
			(stroke
				(width 0.1)
				(type default)
			)
			(layer "F.Fab")
		)
		(fp_line
			(start 0.120396 0.2794)
			(end -0.12065 0.2794)
			(stroke
				(width 0.1)
				(type default)
			)
			(layer "F.Fab")
		)
		(fp_line
			(start -0.12065 0.3048)
			(end -0.67945 0.3048)
			(stroke
				(width 0.1)
				(type default)
			)
			(layer "F.Fab")
		)
		(fp_line
			(start -0.12065 0.2794)
			(end -0.12065 0.3048)
			(stroke
				(width 0.1)
				(type default)
			)
			(layer "F.Fab")
		)
		(fp_line
			(start -0.12065 -0.2794)
			(end 0.12065 -0.2794)
			(stroke
				(width 0.1)
				(type default)
			)
			(layer "F.Fab")
		)
		(fp_line
			(start -0.12065 -0.305054)
			(end -0.12065 -0.2794)
			(stroke
				(width 0.1)
				(type default)
			)
			(layer "F.Fab")
		)
		(fp_line
			(start -0.67945 0.3048)
			(end -0.67945 -0.305054)
			(stroke
				(width 0.1)
				(type default)
			)
			(layer "F.Fab")
		)
		(fp_line
			(start -0.67945 -0.305054)
			(end -0.12065 -0.305054)
			(stroke
				(width 0.1)
				(type default)
			)
			(layer "F.Fab")
		)
		(pad "1" smd circle
			(at -0.40005 0 180)
			(size 0 0)
			(layers "F.Cu" "F.Mask" "F.Paste")
			(net "PD_PCH_GPPC_C10")
		)
		(pad "2" smd circle
			(at 0.40005 0 180)
			(size 0 0)
			(layers "F.Cu" "F.Mask" "F.Paste")
			(net "GND")
		)
	)
	(footprint ""
		(layer "F.Cu")
		(at 342.43899 -70.03796 90)
		(property "Reference" "C153"
			(at 0 0 90)
			(layer "F.SilkS")
			(hide yes)
			(effects
				(font
					(size 1.27 1.27)
				)
			)
		)
		(property "Value" ""
			(at 0 0 90)
			(layer "F.Fab")
			(effects
				(font
					(size 1.27 1.27)
				)
			)
		)
		(duplicate_pad_numbers_are_jumpers no)
		(fp_line
			(start 0.299974 -0.150114)
			(end 0.299974 0.150114)
			(stroke
				(width 0.1)
				(type default)
			)
			(layer "F.Fab")
		)
		(fp_line
			(start -0.299974 -0.150114)
			(end 0.299974 -0.150114)
			(stroke
				(width 0.1)
				(type default)
			)
			(layer "F.Fab")
		)
		(fp_line
			(start 0.299974 0.150114)
			(end -0.299974 0.150114)
			(stroke
				(width 0.1)
				(type default)
			)
			(layer "F.Fab")
		)
		(fp_line
			(start -0.299974 0.150114)
			(end -0.299974 -0.150114)
			(stroke
				(width 0.1)
				(type default)
			)
			(layer "F.Fab")
		)
		(pad "1" smd rect
			(at -0.2667 0 90)
			(size 0.3048 0.381)
			(layers "F.Cu" "F.Mask" "F.Paste")
			(net "DMI_CPU0_PCH_TX_C_DN<0>")
		)
		(pad "2" smd rect
			(at 0.2667 0 90)
			(size 0.3048 0.381)
			(layers "F.Cu" "F.Mask" "F.Paste")
			(net "DMI_CPU0_PCH_TX_DN<0>")
		)
	)
	(footprint ""
		(layer "F.Cu")
		(at 64.614298 -23.554182)
		(property "Reference" "PR3857"
			(at 0 0 0)
			(layer "F.SilkS")
			(hide yes)
			(effects
				(font
					(size 1.27 1.27)
				)
			)
		)
		(property "Value" ""
			(at 0 0 0)
			(layer "F.Fab")
			(effects
				(font
					(size 1.27 1.27)
				)
			)
		)
		(duplicate_pad_numbers_are_jumpers no)
		(fp_line
			(start -1.2954 -0.5842)
			(end 1.2954 -0.5842)
			(stroke
				(width 0.1524)
				(type default)
			)
			(layer "F.SilkS")
		)
		(fp_line
			(start -1.2954 0.5842)
			(end -1.2954 -0.5842)
			(stroke
				(width 0.1524)
				(type default)
			)
			(layer "F.SilkS")
		)
		(fp_line
			(start 1.2954 -0.5842)
			(end 1.2954 0.5842)
			(stroke
				(width 0.1524)
				(type default)
			)
			(layer "F.SilkS")
		)
		(fp_line
			(start 1.2954 0.5842)
			(end -1.2954 0.5842)
			(stroke
				(width 0.1524)
				(type default)
			)
			(layer "F.SilkS")
		)
		(fp_line
			(start -1.1938 -0.406654)
			(end -0.8636 -0.406654)
			(stroke
				(width 0.1)
				(type default)
			)
			(layer "F.Fab")
		)
		(fp_line
			(start -1.1938 0.4064)
			(end -1.1938 -0.406654)
			(stroke
				(width 0.1)
				(type default)
			)
			(layer "F.Fab")
		)
		(fp_line
			(start -0.8636 -0.4572)
			(end 0.8636 -0.4572)
			(stroke
				(width 0.1)
				(type default)
			)
			(layer "F.Fab")
		)
		(fp_line
			(start -0.8636 -0.406654)
			(end -0.8636 -0.4572)
			(stroke
				(width 0.1)
				(type default)
			)
			(layer "F.Fab")
		)
		(fp_line
			(start -0.8636 0.4064)
			(end -1.1938 0.4064)
			(stroke
				(width 0.1)
				(type default)
			)
			(layer "F.Fab")
		)
		(fp_line
			(start -0.8636 0.4318)
			(end -0.8636 0.4064)
			(stroke
				(width 0.1)
				(type default)
			)
			(layer "F.Fab")
		)
		(fp_line
			(start -0.8636 0.4572)
			(end -0.8636 0.4318)
			(stroke
				(width 0.1)
				(type default)
			)
			(layer "F.Fab")
		)
		(fp_line
			(start 0.8636 -0.4572)
			(end 0.8636 -0.406654)
			(stroke
				(width 0.1)
				(type default)
			)
			(layer "F.Fab")
		)
		(fp_line
			(start 0.8636 -0.406654)
			(end 1.1938 -0.406654)
			(stroke
				(width 0.1)
				(type default)
			)
			(layer "F.Fab")
		)
		(fp_line
			(start 0.8636 0.4064)
			(end 0.8636 0.4572)
			(stroke
				(width 0.1)
				(type default)
			)
			(layer "F.Fab")
		)
		(fp_line
			(start 0.8636 0.4572)
			(end -0.8636 0.4572)
			(stroke
				(width 0.1)
				(type default)
			)
			(layer "F.Fab")
		)
		(fp_line
			(start 1.1938 -0.406654)
			(end 1.1938 0.4064)
			(stroke
				(width 0.1)
				(type default)
			)
			(layer "F.Fab")
		)
		(fp_line
			(start 1.1938 0.4064)
			(end 0.8636 0.4064)
			(stroke
				(width 0.1)
				(type default)
			)
			(layer "F.Fab")
		)
		(pad "1" smd rect
			(at -0.7366 0 270)
			(size 0.7112 0.8128)
			(layers "F.Cu" "F.Mask" "F.Paste")
			(net "P12V_AUX")
		)
		(pad "2" smd rect
			(at 0.7366 0 270)
			(size 0.7112 0.8128)
			(layers "F.Cu" "F.Mask" "F.Paste")
			(net "P12V_OCP_AVIN_PD_2")
		)
	)
)
